(kicad_pcb
	(version 20260206)
	(generator "pcbnew")
	(generator_version "10.0")
	(general
		(thickness 1.6)
		(legacy_teardrops no)
	)
	(paper "A4")
	(title_block
		(title "04192023_DAF0TMB3IC0_F0TG_MB_C_brd_V02_OCP.brd")
		(comment 1 "Grand Teton / footprints 1397-1401 of 8354")
	)
	(layers
		(0 "F.Cu" signal "TOP")
		(4 "In1.Cu" signal "GND")
		(6 "In2.Cu" signal "IN1")
		(8 "In3.Cu" signal "GND1")
		(10 "In4.Cu" signal "IN2")
		(12 "In5.Cu" signal "GND2")
		(14 "In6.Cu" signal "IN3")
		(16 "In7.Cu" signal "GND3")
		(18 "In8.Cu" signal "VCC")
		(20 "In9.Cu" signal "VCC1")
		(22 "In10.Cu" signal "GND4")
		(24 "In11.Cu" signal "IN4")
		(26 "In12.Cu" signal "GND5")
		(28 "In13.Cu" signal "IN5")
		(30 "In14.Cu" signal "GND6")
		(32 "In15.Cu" signal "IN6")
		(34 "In16.Cu" signal "GND7")
		(2 "B.Cu" signal "BOTTOM")
		(9 "F.Adhes" user "F.Adhesive")
		(11 "B.Adhes" user "B.Adhesive")
		(13 "F.Paste" user "Package Geometry/Pastemask Top")
		(15 "B.Paste" user "Package Geometry/Pastemask Bottom")
		(5 "F.SilkS" user "Ref Des/Silkscreen Top")
		(7 "B.SilkS" user "Ref Des/Silkscreen Bottom")
		(1 "F.Mask" user "Board Geometry/Soldermask Top")
		(3 "B.Mask" user "Board Geometry/Soldermask Bottom")
		(17 "Dwgs.User" user "User.Drawings")
		(19 "Cmts.User" user "User.Comments")
		(21 "Eco1.User" user "User.Eco1")
		(23 "Eco2.User" user "User.Eco2")
		(25 "Edge.Cuts" user "Board Geometry/Outline")
		(27 "Margin" user)
		(31 "F.CrtYd" user "Package Geometry/Place Bound Top")
		(29 "B.CrtYd" user "Package Geometry/Place Bound Bottom")
		(35 "F.Fab" user "Ref Des/Assembly Top")
		(33 "B.Fab" user "Ref Des/Assembly Bottom")
	)
	(footprint ""
		(layer "F.Cu")
		(at 318.463676 -325.678038)
		(property "Reference" "PL14"
			(at 3.234944 -15.887446 0)
			(unlocked yes)
			(layer "F.SilkS")
			(effects
				(font
					(size 0.7874 0.5842)
					(thickness 0.1524)
				)
				(justify left)
			)
		)
		(property "Value" ""
			(at 0 0 0)
			(layer "F.Fab")
			(effects
				(font
					(size 1.27 1.27)
				)
			)
		)
		(duplicate_pad_numbers_are_jumpers no)
		(fp_line
			(start -3.750056 -5.500116)
			(end -2.393442 -5.500116)
			(stroke
				(width 0.1524)
				(type default)
			)
			(layer "F.SilkS")
		)
		(fp_line
			(start -3.750056 5.500116)
			(end -3.750056 -5.500116)
			(stroke
				(width 0.1524)
				(type default)
			)
			(layer "F.SilkS")
		)
		(fp_line
			(start -2.393442 5.500116)
			(end -3.750056 5.500116)
			(stroke
				(width 0.1524)
				(type default)
			)
			(layer "F.SilkS")
		)
		(fp_line
			(start 2.393442 5.500116)
			(end 3.750056 5.500116)
			(stroke
				(width 0.1524)
				(type default)
			)
			(layer "F.SilkS")
		)
		(fp_line
			(start 3.750056 -5.500116)
			(end 2.393442 -5.500116)
			(stroke
				(width 0.1524)
				(type default)
			)
			(layer "F.SilkS")
		)
		(fp_line
			(start 3.750056 5.500116)
			(end 3.750056 -5.500116)
			(stroke
				(width 0.1524)
				(type default)
			)
			(layer "F.SilkS")
		)
		(fp_poly
			(pts
				(xy -3.9116 -4.249928) (xy -4.9276 -3.741928) (xy -4.9276 -4.757928)
			)
			(stroke
				(width 0)
				(type default)
			)
			(fill yes)
			(layer "F.SilkS")
		)
		(fp_line
			(start -3.750056 -5.500116)
			(end -3.750056 5.500116)
			(stroke
				(width 0.1)
				(type default)
			)
			(layer "F.Fab")
		)
		(fp_line
			(start -3.750056 5.500116)
			(end 3.750056 5.500116)
			(stroke
				(width 0.1)
				(type default)
			)
			(layer "F.Fab")
		)
		(fp_line
			(start 3.750056 -5.500116)
			(end -3.750056 -5.500116)
			(stroke
				(width 0.1)
				(type default)
			)
			(layer "F.Fab")
		)
		(fp_line
			(start 3.750056 5.500116)
			(end 3.750056 -5.500116)
			(stroke
				(width 0.1)
				(type default)
			)
			(layer "F.Fab")
		)
		(fp_poly
			(pts
				(xy -4.9276 -4.757928) (xy -4.9276 -3.741928) (xy -3.9116 -4.249928)
			)
			(stroke
				(width 0)
				(type default)
			)
			(fill yes)
			(layer "F.Fab")
		)
		(pad "1" smd rect
			(at 0 -4.249928 270)
			(size 2.413 4.5212)
			(layers "F.Cu" "F.Mask" "F.Paste")
			(net "SW_PVDDCR_CPU1_P0_SW3")
		)
		(pad "2" smd rect
			(at 0 -1.175004 270)
			(size 1.3716 4.5212)
			(layers "F.Cu" "F.Mask" "F.Paste")
			(net "IND_CPU1_P0_CPL2")
		)
		(pad "3" smd rect
			(at 0 1.175004 270)
			(size 1.3716 4.5212)
			(layers "F.Cu" "F.Mask" "F.Paste")
			(net "IND_CPU1_P0_CPL3")
		)
		(pad "4" smd rect
			(at 0 4.249928 270)
			(size 2.413 4.5212)
			(layers "F.Cu" "F.Mask" "F.Paste")
			(net "PVDDCR_CPU1_P0")
		)
	)
	(footprint ""
		(layer "F.Cu")
		(at 72.708262 -39.319962)
		(property "Reference" "U263"
			(at 3.21056 -1.763268 0)
			(unlocked yes)
			(layer "F.SilkS")
			(effects
				(font
					(size 0.7874 0.5842)
					(thickness 0.1524)
				)
			)
		)
		(property "Value" ""
			(at 0 0 0)
			(layer "F.Fab")
			(effects
				(font
					(size 1.27 1.27)
				)
			)
		)
		(duplicate_pad_numbers_are_jumpers no)
		(fp_line
			(start -1.500124 -1.500124)
			(end -1.004062 -1.500124)
			(stroke
				(width 0.1524)
				(type default)
			)
			(layer "F.SilkS")
		)
		(fp_line
			(start -1.500124 -1.004062)
			(end -1.500124 -1.500124)
			(stroke
				(width 0.1524)
				(type default)
			)
			(layer "F.SilkS")
		)
		(fp_line
			(start -1.500124 1.500124)
			(end -1.500124 1.004062)
			(stroke
				(width 0.1524)
				(type default)
			)
			(layer "F.SilkS")
		)
		(fp_line
			(start -1.004062 1.500124)
			(end -1.500124 1.500124)
			(stroke
				(width 0.1524)
				(type default)
			)
			(layer "F.SilkS")
		)
		(fp_line
			(start 1.004062 -1.500124)
			(end 1.500124 -1.500124)
			(stroke
				(width 0.1524)
				(type default)
			)
			(layer "F.SilkS")
		)
		(fp_line
			(start 1.500124 -1.500124)
			(end 1.500124 -1.004062)
			(stroke
				(width 0.1524)
				(type default)
			)
			(layer "F.SilkS")
		)
		(fp_line
			(start 1.500124 1.004062)
			(end 1.500124 1.500124)
			(stroke
				(width 0.1524)
				(type default)
			)
			(layer "F.SilkS")
		)
		(fp_line
			(start 1.500124 1.500124)
			(end 1.004062 1.500124)
			(stroke
				(width 0.1524)
				(type default)
			)
			(layer "F.SilkS")
		)
		(fp_poly
			(pts
				(xy -2.343912 -2.40284) (xy -3.062224 -1.684274) (xy -1.984502 -1.325118)
			)
			(stroke
				(width 0)
				(type default)
			)
			(fill yes)
			(layer "F.SilkS")
		)
		(fp_line
			(start -1.500124 -1.500124)
			(end 1.500124 -1.500124)
			(stroke
				(width 0.1)
				(type default)
			)
			(layer "F.Fab")
		)
		(fp_line
			(start -1.500124 1.500124)
			(end -1.500124 -1.500124)
			(stroke
				(width 0.1)
				(type default)
			)
			(layer "F.Fab")
		)
		(fp_line
			(start 1.500124 -1.500124)
			(end 1.500124 1.500124)
			(stroke
				(width 0.1)
				(type default)
			)
			(layer "F.Fab")
		)
		(fp_line
			(start 1.500124 1.500124)
			(end -1.500124 1.500124)
			(stroke
				(width 0.1)
				(type default)
			)
			(layer "F.Fab")
		)
		(fp_poly
			(pts
				(xy -2.847848 -1.258062) (xy -2.847848 -0.242062) (xy -1.831848 -0.750062)
			)
			(stroke
				(width 0)
				(type default)
			)
			(fill yes)
			(layer "F.Fab")
		)
		(pad "1" smd rect
			(at -1.400048 -0.750062 270)
			(size 0.2286 0.6096)
			(layers "F.Cu" "F.Mask" "F.Paste")
			(net "INA230_3_A1")
		)
		(pad "2" smd rect
			(at -1.400048 -0.249936 270)
			(size 0.2286 0.6096)
			(layers "F.Cu" "F.Mask" "F.Paste")
			(net "INA230_3_A0")
		)
		(pad "3" smd rect
			(at -1.400048 0.249936 270)
			(size 0.2286 0.6096)
			(layers "F.Cu" "F.Mask" "F.Paste")
			(net "OCP_V3_2_P3V3_ADC_ALERT_R")
		)
		(pad "4" smd rect
			(at -1.400048 0.750062 270)
			(size 0.2286 0.6096)
			(layers "F.Cu" "F.Mask" "F.Paste")
			(net "SMB_INA230_3_3V3AUX_SDA_R1")
		)
		(pad "5" smd rect
			(at -0.750062 1.400048)
			(size 0.2286 0.6096)
			(layers "F.Cu" "F.Mask" "F.Paste")
			(net "SMB_INA230_3_3V3AUX_SCL_R1")
		)
		(pad "6" smd rect
			(at -0.249936 1.400048)
			(size 0.2286 0.6096)
			(layers "F.Cu" "F.Mask" "F.Paste")
			(net "NC_INA230_3_NC0")
		)
		(pad "7" smd rect
			(at 0.249936 1.400048)
			(size 0.2286 0.6096)
			(layers "F.Cu" "F.Mask" "F.Paste")
			(net "NC_INA230_3_NC1")
		)
		(pad "8" smd rect
			(at 0.750062 1.400048)
			(size 0.2286 0.6096)
			(layers "F.Cu" "F.Mask" "F.Paste")
			(net "NC_INA230_3_NC2")
		)
		(pad "9" smd rect
			(at 1.400048 0.750062 270)
			(size 0.2286 0.6096)
			(layers "F.Cu" "F.Mask" "F.Paste")
			(net "P3V3_AUX")
		)
		(pad "10" smd rect
			(at 1.400048 0.249936 270)
			(size 0.2286 0.6096)
			(layers "F.Cu" "F.Mask" "F.Paste")
			(net "GND")
		)
		(pad "11" smd rect
			(at 1.400048 -0.249936 270)
			(size 0.2286 0.6096)
			(layers "F.Cu" "F.Mask" "F.Paste")
			(net "P3V3_OCP_V3_2_R")
		)
		(pad "12" smd rect
			(at 1.400048 -0.750062 270)
			(size 0.2286 0.6096)
			(layers "F.Cu" "F.Mask" "F.Paste")
			(net "VSENSE_P12V_INA230_3_INN")
		)
		(pad "13" smd rect
			(at 0.750062 -1.400048)
			(size 0.2286 0.6096)
			(layers "F.Cu" "F.Mask" "F.Paste")
			(net "VSENSE_P12V_INA230_3_INP")
		)
		(pad "14" smd rect
			(at 0.249936 -1.400048)
			(size 0.2286 0.6096)
			(layers "F.Cu" "F.Mask" "F.Paste")
			(net "NC_INA230_3_NC3")
		)
		(pad "15" smd rect
			(at -0.249936 -1.400048)
			(size 0.2286 0.6096)
			(layers "F.Cu" "F.Mask" "F.Paste")
			(net "NC_INA230_3_NC4")
		)
		(pad "16" smd rect
			(at -0.750062 -1.400048)
			(size 0.2286 0.6096)
			(layers "F.Cu" "F.Mask" "F.Paste")
			(net "NC_INA230_3_NC5")
		)
		(pad "TH" smd rect
			(at 0 0)
			(size 1.7018 1.7018)
			(layers "F.Cu" "F.Mask" "F.Paste")
			(net "GND")
		)
		(zone
			(layer "F.Cu")
			(hatch none 0.5)
			(connect_pads
				(clearance 0)
			)
			(min_thickness 0.25)
			(keepout
				(tracks not_allowed)
				(vias allowed)
				(pads allowed)
				(copperpour not_allowed)
				(footprints allowed)
			)
			(placement
				(enabled no)
				(sheetname "")
			)
			(fill
				(thermal_gap 0.5)
				(thermal_bridge_width 0.5)
				(island_removal_mode 0)
			)
			(polygon
				(pts
					(xy 71.663814 -39.345362) (xy 71.663814 -40.36441) (xy 73.75271 -40.36441) (xy 73.75271 -38.275514)
					(xy 71.663814 -38.275514) (xy 71.663814 -39.319962) (xy 71.806562 -39.319962) (xy 71.806562 -38.418262)
					(xy 73.609962 -38.418262) (xy 73.609962 -40.221662) (xy 71.806562 -40.221662) (xy 71.806562 -39.345362)
				)
			)
		)
	)
	(footprint ""
		(layer "F.Cu")
		(at 429.276764 -355.997764 90)
		(property "Reference" "PC9"
			(at 0 0 90)
			(layer "F.SilkS")
			(hide yes)
			(effects
				(font
					(size 1.27 1.27)
				)
			)
		)
		(property "Value" ""
			(at 0 0 90)
			(layer "F.Fab")
			(effects
				(font
					(size 1.27 1.27)
				)
			)
		)
		(duplicate_pad_numbers_are_jumpers no)
		(fp_line
			(start 0.7874 -0.4064)
			(end 0.7874 0.4064)
			(stroke
				(width 0.1524)
				(type default)
			)
			(layer "F.SilkS")
		)
		(fp_line
			(start -0.7874 -0.4064)
			(end 0.7874 -0.4064)
			(stroke
				(width 0.1524)
				(type default)
			)
			(layer "F.SilkS")
		)
		(fp_line
			(start 0.7874 0.4064)
			(end -0.7874 0.4064)
			(stroke
				(width 0.1524)
				(type default)
			)
			(layer "F.SilkS")
		)
		(fp_line
			(start -0.7874 0.4064)
			(end -0.7874 -0.4064)
			(stroke
				(width 0.1524)
				(type default)
			)
			(layer "F.SilkS")
		)
		(fp_line
			(start -0.12065 -0.305054)
			(end -0.12065 -0.2794)
			(stroke
				(width 0.1)
				(type default)
			)
			(layer "F.Fab")
		)
		(fp_line
			(start -0.67945 -0.305054)
			(end -0.12065 -0.305054)
			(stroke
				(width 0.1)
				(type default)
			)
			(layer "F.Fab")
		)
		(fp_line
			(start 0.67945 -0.3048)
			(end 0.67945 0.3048)
			(stroke
				(width 0.1)
				(type default)
			)
			(layer "F.Fab")
		)
		(fp_line
			(start 0.12065 -0.3048)
			(end 0.67945 -0.3048)
			(stroke
				(width 0.1)
				(type default)
			)
			(layer "F.Fab")
		)
		(fp_line
			(start 0.12065 -0.2794)
			(end 0.12065 -0.3048)
			(stroke
				(width 0.1)
				(type default)
			)
			(layer "F.Fab")
		)
		(fp_line
			(start -0.12065 -0.2794)
			(end 0.12065 -0.2794)
			(stroke
				(width 0.1)
				(type default)
			)
			(layer "F.Fab")
		)
		(fp_line
			(start 0.120396 0.2794)
			(end -0.12065 0.2794)
			(stroke
				(width 0.1)
				(type default)
			)
			(layer "F.Fab")
		)
		(fp_line
			(start -0.12065 0.2794)
			(end -0.12065 0.3048)
			(stroke
				(width 0.1)
				(type default)
			)
			(layer "F.Fab")
		)
		(fp_line
			(start 0.67945 0.3048)
			(end 0.120396 0.3048)
			(stroke
				(width 0.1)
				(type default)
			)
			(layer "F.Fab")
		)
		(fp_line
			(start 0.120396 0.3048)
			(end 0.120396 0.2794)
			(stroke
				(width 0.1)
				(type default)
			)
			(layer "F.Fab")
		)
		(fp_line
			(start -0.12065 0.3048)
			(end -0.67945 0.3048)
			(stroke
				(width 0.1)
				(type default)
			)
			(layer "F.Fab")
		)
		(fp_line
			(start -0.67945 0.3048)
			(end -0.67945 -0.305054)
			(stroke
				(width 0.1)
				(type default)
			)
			(layer "F.Fab")
		)
		(pad "1" smd circle
			(at -0.40005 0 90)
			(size 0 0)
			(layers "F.Cu" "F.Mask" "F.Paste")
			(net "PVDD11_S3_P0_VCCS")
		)
		(pad "2" smd circle
			(at 0.40005 0 90)
			(size 0 0)
			(layers "F.Cu" "F.Mask" "F.Paste")
			(net "GND")
		)
	)
	(footprint ""
		(layer "F.Cu")
		(at 318.300608 -22.57933 90)
		(property "Reference" "R1343"
			(at 0 0 90)
			(layer "F.SilkS")
			(hide yes)
			(effects
				(font
					(size 1.27 1.27)
				)
			)
		)
		(property "Value" ""
			(at 0 0 90)
			(layer "F.Fab")
			(effects
				(font
					(size 1.27 1.27)
				)
			)
		)
		(duplicate_pad_numbers_are_jumpers no)
		(fp_line
			(start 0.7874 -0.4064)
			(end 0.7874 0.4064)
			(stroke
				(width 0.1524)
				(type default)
			)
			(layer "F.SilkS")
		)
		(fp_line
			(start -0.7874 -0.4064)
			(end 0.7874 -0.4064)
			(stroke
				(width 0.1524)
				(type default)
			)
			(layer "F.SilkS")
		)
		(fp_line
			(start 0.7874 0.4064)
			(end -0.7874 0.4064)
			(stroke
				(width 0.1524)
				(type default)
			)
			(layer "F.SilkS")
		)
		(fp_line
			(start -0.7874 0.4064)
			(end -0.7874 -0.4064)
			(stroke
				(width 0.1524)
				(type default)
			)
			(layer "F.SilkS")
		)
		(fp_line
			(start -0.12065 -0.305054)
			(end -0.12065 -0.2794)
			(stroke
				(width 0.1)
				(type default)
			)
			(layer "F.Fab")
		)
		(fp_line
			(start -0.67945 -0.305054)
			(end -0.12065 -0.305054)
			(stroke
				(width 0.1)
				(type default)
			)
			(layer "F.Fab")
		)
		(fp_line
			(start 0.67945 -0.3048)
			(end 0.67945 0.3048)
			(stroke
				(width 0.1)
				(type default)
			)
			(layer "F.Fab")
		)
		(fp_line
			(start 0.12065 -0.3048)
			(end 0.67945 -0.3048)
			(stroke
				(width 0.1)
				(type default)
			)
			(layer "F.Fab")
		)
		(fp_line
			(start 0.12065 -0.2794)
			(end 0.12065 -0.3048)
			(stroke
				(width 0.1)
				(type default)
			)
			(layer "F.Fab")
		)
		(fp_line
			(start -0.12065 -0.2794)
			(end 0.12065 -0.2794)
			(stroke
				(width 0.1)
				(type default)
			)
			(layer "F.Fab")
		)
		(fp_line
			(start 0.120396 0.2794)
			(end -0.12065 0.2794)
			(stroke
				(width 0.1)
				(type default)
			)
			(layer "F.Fab")
		)
		(fp_line
			(start -0.12065 0.2794)
			(end -0.12065 0.3048)
			(stroke
				(width 0.1)
				(type default)
			)
			(layer "F.Fab")
		)
		(fp_line
			(start 0.67945 0.3048)
			(end 0.120396 0.3048)
			(stroke
				(width 0.1)
				(type default)
			)
			(layer "F.Fab")
		)
		(fp_line
			(start 0.120396 0.3048)
			(end 0.120396 0.2794)
			(stroke
				(width 0.1)
				(type default)
			)
			(layer "F.Fab")
		)
		(fp_line
			(start -0.12065 0.3048)
			(end -0.67945 0.3048)
			(stroke
				(width 0.1)
				(type default)
			)
			(layer "F.Fab")
		)
		(fp_line
			(start -0.67945 0.3048)
			(end -0.67945 -0.305054)
			(stroke
				(width 0.1)
				(type default)
			)
			(layer "F.Fab")
		)
		(pad "1" smd circle
			(at -0.40005 0 90)
			(size 0 0)
			(layers "F.Cu" "F.Mask" "F.Paste")
			(net "P3V3_AUX")
		)
		(pad "2" smd circle
			(at 0.40005 0 90)
			(size 0 0)
			(layers "F.Cu" "F.Mask" "F.Paste")
			(net "SCM_JTAG_MUX_S1")
		)
	)
	(footprint ""
		(layer "F.Cu")
		(at 205.214982 -119.721376)
		(property "Reference" "R3066"
			(at 0 0 0)
			(layer "F.SilkS")
			(hide yes)
			(effects
				(font
					(size 1.27 1.27)
				)
			)
		)
		(property "Value" ""
			(at 0 0 0)
			(layer "F.Fab")
			(effects
				(font
					(size 1.27 1.27)
				)
			)
		)
		(duplicate_pad_numbers_are_jumpers no)
		(fp_line
			(start -0.7874 -0.4064)
			(end 0.7874 -0.4064)
			(stroke
				(width 0.1524)
				(type default)
			)
			(layer "F.SilkS")
		)
		(fp_line
			(start -0.7874 0.4064)
			(end -0.7874 -0.4064)
			(stroke
				(width 0.1524)
				(type default)
			)
			(layer "F.SilkS")
		)
		(fp_line
			(start 0.7874 -0.4064)
			(end 0.7874 0.4064)
			(stroke
				(width 0.1524)
				(type default)
			)
			(layer "F.SilkS")
		)
		(fp_line
			(start 0.7874 0.4064)
			(end -0.7874 0.4064)
			(stroke
				(width 0.1524)
				(type default)
			)
			(layer "F.SilkS")
		)
		(fp_line
			(start -0.67945 -0.305054)
			(end -0.12065 -0.305054)
			(stroke
				(width 0.1)
				(type default)
			)
			(layer "F.Fab")
		)
		(fp_line
			(start -0.67945 0.3048)
			(end -0.67945 -0.305054)
			(stroke
				(width 0.1)
				(type default)
			)
			(layer "F.Fab")
		)
		(fp_line
			(start -0.12065 -0.305054)
			(end -0.12065 -0.2794)
			(stroke
				(width 0.1)
				(type default)
			)
			(layer "F.Fab")
		)
		(fp_line
			(start -0.12065 -0.2794)
			(end 0.12065 -0.2794)
			(stroke
				(width 0.1)
				(type default)
			)
			(layer "F.Fab")
		)
		(fp_line
			(start -0.12065 0.2794)
			(end -0.12065 0.3048)
			(stroke
				(width 0.1)
				(type default)
			)
			(layer "F.Fab")
		)
		(fp_line
			(start -0.12065 0.3048)
			(end -0.67945 0.3048)
			(stroke
				(width 0.1)
				(type default)
			)
			(layer "F.Fab")
		)
		(fp_line
			(start 0.120396 0.2794)
			(end -0.12065 0.2794)
			(stroke
				(width 0.1)
				(type default)
			)
			(layer "F.Fab")
		)
		(fp_line
			(start 0.120396 0.3048)
			(end 0.120396 0.2794)
			(stroke
				(width 0.1)
				(type default)
			)
			(layer "F.Fab")
		)
		(fp_line
			(start 0.12065 -0.3048)
			(end 0.67945 -0.3048)
			(stroke
				(width 0.1)
				(type default)
			)
			(layer "F.Fab")
		)
		(fp_line
			(start 0.12065 -0.2794)
			(end 0.12065 -0.3048)
			(stroke
				(width 0.1)
				(type default)
			)
			(layer "F.Fab")
		)
		(fp_line
			(start 0.67945 -0.3048)
			(end 0.67945 0.3048)
			(stroke
				(width 0.1)
				(type default)
			)
			(layer "F.Fab")
		)
		(fp_line
			(start 0.67945 0.3048)
			(end 0.120396 0.3048)
			(stroke
				(width 0.1)
				(type default)
			)
			(layer "F.Fab")
		)
		(pad "1" smd circle
			(at -0.40005 0)
			(size 0 0)
			(layers "F.Cu" "F.Mask" "F.Paste")
			(net "FM_SMB_1_ALERT_GPU_ISO_R_N")
		)
		(pad "2" smd circle
			(at 0.40005 0)
			(size 0 0)
			(layers "F.Cu" "F.Mask" "F.Paste")
			(net "FM_SMB_1_ALERT_GPU_ISO_N")
		)
	)
)
